FILE_TYPE = MACRO_DRAWING;
SET COLOR_WIRE YELLOW;
SET COLOR_PROP ORANGE;
SET COLOR_DOT WHITE;
SET COLOR_ARC YELLOW;
SET COLOR_BODY GREEN;
SET COLOR_NOTE PURPLE;
SET PROP_DISPLAY VALUE;
SET PAGE_NUMBER P5;
FORCEADD QUANTA_TITLE_BLOCK_C..1
(-100 100);
FORCEPROP 1 LAST CUSTOM_TXT_CDS <NAME_2>
J 0
(-3275 150);
FORCEPROP 1 LAST CUSTOM_TXT_CDS <NAME_1>
J 0
(-3275 275);
FORCEPROP 1 LAST CUSTOM_TXT_CDS <Q_NUMBER>
J 0
(-1503 203);
DISPLAY 1.212766 (-1503 203);
FORCEPROP 1 LAST CUSTOM_TXT_CDS <Q_PROJ>
J 0
(-2482 202);
DISPLAY 1.212766 (-2482 202);
FORCEPROP 1 LAST CUSTOM_TXT_CDS <Q_REV>
J 0
(-284 203);
DISPLAY 1.212766 (-284 203);
FORCEPROP 1 LAST CUSTOM_TXT_CDS <CON_LAST_MODIFIED>
J 0
(-1985 115);
DISPLAY 0.978723 (-1985 115);
FORCEPROP 1 LAST CUSTOM_TXT_CDS <CON_PAGE_NUM> OF <CON_TOTAL_PAGES>
J 0
(-546 118);
DISPLAY 0.978723 (-546 118);
FORCEPROP 1 LAST Q_TITLE BLOCK DIAGRAM - SYSTEM
J 0
(-9350 175);
DISPLAY 2.446809 (-9350 175);
PAINT GREEN (-9350 175);
FORCEPROP 2 LAST CDS_LIB pure_quanta
J 0
(-100 100);
DISPLAY INVISIBLE (-100 100);
FORCEPROP 1 LAST CDS_LMAN_SYM_OUTLINE -9475,6775,100,-125
J 0
(-100 100);
DISPLAY 0.468085 (-100 100);
PAINT GREEN (-100 100);
DISPLAY INVISIBLE (-100 100);
FORCEPROP 2 LAST PAGE_BORDER TRUE
J 0
(-7990 5350);
DISPLAY 0.638298 (-7990 5350);
PAINT PINK (-7990 5350);
DISPLAY INVISIBLE (-7990 5350);
FORCEPROP 2 LAST CDS_XR_PAGE_TITLE CR-5 : @T6G_MB_LIB.T6G(SCH_1):PAGE5
J 0
(-7990 5350);
DISPLAY 0.638298 (-7990 5350);
PAINT PINK (-7990 5350);
DISPLAY INVISIBLE (-7990 5350);
FORCEPROP 2 LAST CUSTOM_TXT_CDS <XR_PAGE_TITLE>
J 0
(-7990 5350);
DISPLAY 0.638298 (-7990 5350);
PAINT PINK (-7990 5350);
DISPLAY INVISIBLE (-7990 5350);
FORCEPROP 1 LAST COMMENT_BODY TRUE
J 0
(-88 87);
DISPLAY 0.978723 (-88 87);
PAINT GREEN (-88 87);
DISPLAY INVISIBLE (-88 87);
FORCEPROP 1 LAST Q_DEPT BU9
J 1
(-3863 149);
DISPLAY 1.957447 (-3863 149);
PAINT GREEN (-3863 149);
DISPLAY INVISIBLE (-3863 149);
FORCEPROP 0 LAST CDS_CON_LAST_MODIFIED Thu Aug 24 10:13:29 2023
J 0
(-1985 115);
DISPLAY INVISIBLE (-1985 115);
FORCENOTE
$CDS_IMAGE|Grand_Teton_Inference_8 Retimer_Block_Diagram_20230203_REV3-MB.jpg|5986|6192
(-4800 3525) 0;
DISPLAY LEFT (-4800 3525);
QUIT
